# S9S_MB_2U (Grand Teton) — schematic parts with pin connectivity, parts 2659–2809 of 6093; source: Cadence DE-HDL packaged netlist (pstxprt.dat, pstxnet.dat, pstchip.dat)

PR226  Q_RES  2.2 1% CHIP  pkg 0402LF  page 289 : 1 = PVCCFA_EHV_FIVRA_CPU1_PVCC1 ; 2 = PVCCFA_EHV_FIVRA_CPU1_VDD1
PR227  Q_RES  2.2 1% CHIP  pkg 0402LF  page 289 : 1 = PVCCFA_EHV_FIVRA_CPU1_PVCC2 ; 2 = PVCCFA_EHV_FIVRA_CPU1_VDD2
PR242  Q_RES  0 5% CHIP  pkg 0402LF  page 284 : 1 = SH_PVCCFA_EHV_FIVRA_CPU1 ; 2 = SH_PVCCFA_EHV_FIVRA_CPU1_R
PR250  Q_RES  2.2 1% CHIP  pkg 0402LF  page 294 : 1 = PVCCFA_EHV_CPU1_PVCC ; 2 = PVCCFA_EHV_CPU1_VDD1
PR254  Q_RES  2.2 1% CHIP  pkg 0402LF  page 293 : 1 = PVCCFA_EHV_CPU1_PVCC ; 2 = PVCCINFAON_CPU1_VDD1
PR255  Q_RES  2.2 1% CHIP  pkg 0402LF  page 293 : 1 = PVCCFA_EHV_CPU1_PVCC ; 2 = PVCCINFAON_CPU1_VDD2
PR258  Q_RES  28K 1% EMPTY  pkg 0402LF  page 292 : 1 = PVCCINFAON_CPU1_VREF ; 2 = PVCCINFAON_CPU1_ADDR
PR259  Q_RES  8.45K 1% CHIP  pkg 0402LF  page 292 : 1 = PVCCINFAON_CPU1_ADDR ; 2 = GND
PR260  Q_RES  0 5% EMPTY  pkg 0402LF  page 292 : 1 = P12V_AUX ; 2 = PVCCINFAON_CPU1_CSPIN
PR261  Q_RES  0 5% CHIP  pkg 0402LF  page 292 : 1 = P12V_AUX ; 2 = PVCCINFAON_CPU1_VIN_CSNIN
PR273  Q_RES  0 5% CHIP  pkg 0402LF  page 292 : 1 = SH_PVCCINFAON_CPU1 ; 2 = SH_PVCCINFAON_CPU1_R
PR274  Q_RES  0 5% CHIP  pkg 0402LF  page 292 : 1 = SH_PVCCFA_EHV_CPU1 ; 2 = SH_PVCCFA_EHV_CPU1_R
PR275  Q_RES  0 5% CHIP  pkg 0402LF  page 292 : 1 = PVCCINFAON_CPU1_CSPIN ; 2 = GND
PR276  Q_RES  1K 1% EMPTY  pkg 0402LF  page 292 : 1 = PVCCINFAON_CPU1_VIN_CSNIN ; 2 = GND
PR283  Q_RES  1 1% CHIP  pkg 0402LF  page 292 : 1 = PVCCINFAON_CPU1_VCC ; 2 = P3V3_AUX
PR285  Q_RES  8.87K 1% EMPTY  pkg 0402LF  page 288 : 1 = PVCCIN_CPU1_LSET8 ; 2 = GND
PR286  Q_RES  8.87K 1% EMPTY  pkg 0402LF  page 288 : 1 = PVCCIN_CPU1_LSET7 ; 2 = GND
PR287  Q_RES  2.2 1% CHIP  pkg 0402LF  page 288 : 1 = PVCCIN_CPU1_PVCC ; 2 = PVCCIN_CPU1_VDD8
PR288  Q_RES  2.2 1% CHIP  pkg 0402LF  page 288 : 1 = PVCCIN_CPU1_PVCC ; 2 = PVCCIN_CPU1_VDD7
PR289  Q_RES  0 5% CHIP  pkg 0402LF  page 288 : 1 = PVCCIN_CPU1_VOS8 ; 2 = PVCCIN_CPU1
PR290  Q_RES  0 5% CHIP  pkg 0402LF  page 288 : 1 = PVCCIN_CPU1_VOS7 ; 2 = PVCCIN_CPU1
PR291  Q_RES  8.87K 1% EMPTY  pkg 0402LF  page 287 : 1 = PVCCIN_CPU1_LSET6 ; 2 = GND
PR292  Q_RES  8.87K 1% EMPTY  pkg 0402LF  page 287 : 1 = PVCCIN_CPU1_LSET5 ; 2 = GND
PR293  Q_RES  2.2 1% CHIP  pkg 0402LF  page 287 : 1 = PVCCIN_CPU1_PVCC ; 2 = PVCCIN_CPU1_VDD6
PR294  Q_RES  2.2 1% CHIP  pkg 0402LF  page 287 : 1 = PVCCIN_CPU1_PVCC ; 2 = PVCCIN_CPU1_VDD5
PR295  Q_RES  0 5% CHIP  pkg 0402LF  page 287 : 1 = PVCCIN_CPU1_VOS6 ; 2 = PVCCIN_CPU1
PR296  Q_RES  0 5% CHIP  pkg 0402LF  page 287 : 1 = PVCCIN_CPU1_VOS5 ; 2 = PVCCIN_CPU1
PR297  Q_RES  8.87K 1% EMPTY  pkg 0402LF  page 286 : 1 = PVCCIN_CPU1_LSET4 ; 2 = GND
PR298  Q_RES  8.87K 1% EMPTY  pkg 0402LF  page 286 : 1 = PVCCIN_CPU1_LSET3 ; 2 = GND
PR299  Q_RES  2.2 1% CHIP  pkg 0402LF  page 286 : 1 = PVCCIN_CPU1_PVCC ; 2 = PVCCIN_CPU1_VDD4
PR300  Q_RES  2.2 1% CHIP  pkg 0402LF  page 286 : 1 = PVCCIN_CPU1_PVCC ; 2 = PVCCIN_CPU1_VDD3
PR301  Q_RES  0 5% CHIP  pkg 0402LF  page 286 : 1 = PVCCIN_CPU1_VOS4 ; 2 = PVCCIN_CPU1
PR302  Q_RES  0 5% CHIP  pkg 0402LF  page 286 : 1 = PVCCIN_CPU1_VOS3 ; 2 = PVCCIN_CPU1
PR303  Q_RES  0 5% CHIP  pkg 0402LF  page 284 : 1 = P12V_AUX ; 2 = PVCCIN_CPU1_VIN_CSNIN
PR304  Q_RES  0 5% EMPTY  pkg 0402LF  page 284 : 1 = P12V_AUX ; 2 = PVCCIN_CPU1_CSPIN
PR305  Q_RES  0 5% CHIP  pkg 0402LF  page 284 : 1 = PVCCIN_CPU1_CSPIN ; 2 = GND
PR306  Q_RES  28K 1% EMPTY  pkg 0402LF  page 284 : 1 = PVCCIN_CPU1_VREF ; 2 = PVCCIN_CPU1_ADDR
PR313  Q_RES  1K 1% EMPTY  pkg 0402LF  page 284 : 1 = PVCCIN_CPU1_VIN_CSNIN ; 2 = GND
PR317  Q_RES  0 5% CHIP  pkg 0402LF  page 284 : 1 = SH_PVCCIN_CPU1 ; 2 = SH_PVCCIN_CPU1_R
PR318  Q_RES  5.23K 1% CHIP  pkg 0402LF  page 284 : 1 = PVCCIN_CPU1_ADDR ; 2 = GND
PR323  Q_RES  1 1% CHIP  pkg 0402LF  page 284 : 1 = PVCCIN_CPU1_VCC ; 2 = P3V3_AUX
PR325  Q_RES  8.87K 1% EMPTY  pkg 0402LF  page 285 : 1 = PVCCIN_CPU1_LSET2 ; 2 = GND
PR326  Q_RES  8.87K 1% EMPTY  pkg 0402LF  page 285 : 1 = PVCCIN_CPU1_LSET1 ; 2 = GND
PR327  Q_RES  2.2 1% CHIP  pkg 0402LF  page 285 : 1 = PVCCIN_CPU1_PVCC ; 2 = PVCCIN_CPU1_VDD2
PR328  Q_RES  2.2 1% CHIP  pkg 0402LF  page 285 : 1 = PVCCIN_CPU1_PVCC ; 2 = PVCCIN_CPU1_VDD1
PR329  Q_RES  0 5% CHIP  pkg 0402LF  page 285 : 1 = PVCCIN_CPU1_VOS2 ; 2 = PVCCIN_CPU1
PR330  Q_RES  0 5% CHIP  pkg 0402LF  page 285 : 1 = PVCCIN_CPU1_VOS1 ; 2 = PVCCIN_CPU1
PR338  Q_RES  0 5% CHIP  pkg 0402LF  page 262 : 1 = P1V05_PCH_AUX_MODE ; 2 = GND
PR345  Q_RES  0 5% CHIP  pkg 0402LF  page 266 : 1 = SH_PVCCFA_EHV_FIVRA_CPU0 ; 2 = SH_PVCCFA_EHV_FIVRA_CPU0_R
PR353  Q_RES  8.87K 1% EMPTY  pkg 0402LF  page 271 : 1 = PVCCFA_EHV_FIVRA_CPU0_LSET2 ; 2 = GND
PR354  Q_RES  8.87K 1% EMPTY  pkg 0402LF  page 271 : 1 = PVCCFA_EHV_FIVRA_CPU0_LSET1 ; 2 = GND
PR355  Q_RES  2.2 1% CHIP  pkg 0402LF  page 271 : 1 = PVCCFA_EHV_FIVRA_CPU0_PVCC1 ; 2 = PVCCFA_EHV_FIVRA_CPU0_VDD1
PR356  Q_RES  2.2 1% CHIP  pkg 0402LF  page 271 : 1 = PVCCFA_EHV_FIVRA_CPU0_PVCC2 ; 2 = PVCCFA_EHV_FIVRA_CPU0_VDD2
PR357  Q_RES  28K 1% EMPTY  pkg 0402LF  page 278 : 1 = PVCCD_HV_CPU0_VREF ; 2 = PVCCD_HV_CPU0_ADDR
PR358  Q_RES  3.57K 1% CHIP  pkg 0402LF  page 278 : 1 = GND ; 2 = PVCCD_HV_CPU0_ADDR
PR369  Q_RES  1K 1% EMPTY  pkg 0402LF  page 278 : 1 = PVCCD_HV_CPU0_ISENSE_P ; 2 = GND
PR370  Q_RES  1K 1% CHIP  pkg 0402LF  page 278 : 1 = P3V3_AUX ; 2 = PVCCD_HV_CPU0_PIN_ALT
PR371  Q_RES  0 5% CHIP  pkg 0402LF  page 278 : 1 = SH_PVCCD_HV_CPU0 ; 2 = SH_PVCCD_HV_CPU0_R
PR372  Q_RES  1K 1% CHIP  pkg 0402LF  page 278 : 1 = P3V3_AUX ; 2 = PVCCD_HV_CPU0_FAULT
PR373  Q_RES  1K 1% EMPTY  pkg 0402LF  page 278 : 1 = PVCCD_HV_CPU0_ISENSE_N ; 2 = GND
PR375  Q_RES  1 1% CHIP  pkg 0402LF  page 278 : 1 = PVCCD_HV_CPU0_VCC ; 2 = P3V3_AUX
PR380  Q_RES  2.2 1% CHIP  pkg 0402LF  page 279 : 1 = PVCCFA_EHV_CPU0_PVCC ; 2 = PVCCD_HV_CPU0_VDD1
PR389  Q_RES  1 1% CHIP  pkg 0402LF  page 259 : 1 = P3V3_AUX_VDRV ; 2 = P3V3_AUX_VCC
PR395  Q_RES  0 5% CHIP  pkg 0402LF  page 263 : 1 = P3V3_AUX ; 2 = PVCC1_AUX
PR396  Q_RES  0 5% EMPTY  pkg 0402LF  page 263 : 1 = P5V_AUX ; 2 = PVCC1_AUX
PR400  Q_RES  10K 1% EMPTY  pkg 0402LF  page 266 : 1 = PVCCIN_CPU0_ATSEN ; 2 = GND
PR402  Q_RES  0 5% CHIP  pkg 0402LF  page 267 : 1 = P5V ; 2 = PVCCIN_CPU0_PVCC
PR403  Q_RES  0 5% EMPTY  pkg 0402LF  page 267 : 1 = P3V3 ; 2 = PVCCIN_CPU0_PVCC
PR409  Q_RES  0 5% EMPTY  pkg 0402LF  page 278 : 1 = PVCCD_HV_CPU0_ISYS_R ; 2 = PVCCD_HV_CPU0_NVDIMM_ISENSE
PR410  Q_RES  0 5% EMPTY  pkg 0402LF  page 296 : 1 = PVCCD_HV_CPU1_ISYS_R ; 2 = PVCCD_HV_CPU1_NVDIMM_ISENSE
PR435  Q_RES  10K 1% EMPTY  pkg 0402LF  page 274 : 1 = PVCCINFAON_CPU0_ATSEN ; 2 = GND
PR436  Q_RES  10K 1% EMPTY  pkg 0402LF  page 274 : 1 = PVCCFA_EHV_CPU0_BTSEN ; 2 = GND
PR442  Q_RES  0 5% CHIP  pkg 0402LF  page 276 : 1 = P5V ; 2 = PVCCFA_EHV_CPU0_PVCC
PR443  Q_RES  0 5% EMPTY  pkg 0402LF  page 276 : 1 = P3V3 ; 2 = PVCCFA_EHV_CPU0_PVCC
PR444  Q_RES  0 5% CHIP  pkg 0402LF  page 271 : 1 = P5V ; 2 = PVCCFA_EHV_FIVRA_CPU0_PVCC1
PR447  Q_RES  0 5% CHIP  pkg 0402LF  page 271 : 1 = P5V ; 2 = PVCCFA_EHV_FIVRA_CPU0_PVCC2
PR451  Q_RES  10K 1% EMPTY  pkg 0402LF  page 266 : 1 = PVCCFA_EHV_FIVRA_CPU0_BTSEN ; 2 = GND
PR453  Q_RES  10K 1% EMPTY  pkg 0402LF  page 284 : 1 = PVCCFA_EHV_FIVRA_CPU1_BTSEN ; 2 = GND
PR501  Q_RES  8.25K 0.1% CHIP  pkg 0402LF  page 282 : 1 = PVNN_MAIN_CPU0_FB ; 2 = PVNN_MAIN_CPU0_FB_RC
PR502  Q_RES  8.25K 0.1% CHIP  pkg 0402LF  page 300 : 1 = PVNN_MAIN_CPU1_FB ; 2 = PVNN_MAIN_CPU1_FB_RC
PR519  Q_RES  100 1% CHIP  pkg 0402LF  page 274 : 1 = VSENSE_PVCCINFAON_CPU0_DN ; 2 = GND
PR520  Q_RES  100 1% CHIP  pkg 0402LF  page 274 : 1 = VSENSE_PVCCFA_EHV_CPU0_DN ; 2 = GND
PR521  Q_RES  100 1% CHIP  pkg 0402LF  page 274 : 1 = VSENSE_PVCCINFAON_CPU0_DP ; 2 = PVCCINFAON_CPU0
PR522  Q_RES  100 1% CHIP  pkg 0402LF  page 274 : 1 = VSENSE_PVCCFA_EHV_CPU0_DP ; 2 = PVCCFA_EHV_CPU0
PR527  Q_RES  100 1% CHIP  pkg 0402LF  page 266 : 1 = VSENSE_PVCCIN_CPU0_DN ; 2 = GND
PR531  Q_RES  100 1% CHIP  pkg 0402LF  page 266 : 1 = VSENSE_PVCCIN_CPU0_DP ; 2 = PVCCIN_CPU0
PR558  Q_RES  100 1% CHIP  pkg 0402LF  page 296 : 1 = VSENSE_PVCCD_HV_CPU1_DN ; 2 = GND
PR559  Q_RES  100 1% CHIP  pkg 0402LF  page 296 : 1 = VSENSE_PVCCD_HV_CPU1_DP ; 2 = PVCCD_HV_CPU1
PR560  Q_RES  100 1% CHIP  pkg 0402LF  page 284 : 1 = VSENSE_PVCCFA_EHV_FIVRA_CPU1_DN ; 2 = GND
PR561  Q_RES  100 1% CHIP  pkg 0402LF  page 284 : 1 = VSENSE_PVCCFA_EHV_FIVRA_CPU1_DP ; 2 = PVCCFA_EHV_FIVRA_CPU1
PR566  Q_RES  100 1% CHIP  pkg 0402LF  page 292 : 1 = VSENSE_PVCCINFAON_CPU1_DN ; 2 = GND
PR567  Q_RES  100 1% CHIP  pkg 0402LF  page 292 : 1 = VSENSE_PVCCFA_EHV_CPU1_DN ; 2 = GND
PR568  Q_RES  100 1% CHIP  pkg 0402LF  page 292 : 1 = VSENSE_PVCCINFAON_CPU1_DP ; 2 = PVCCINFAON_CPU1
PR569  Q_RES  100 1% CHIP  pkg 0402LF  page 292 : 1 = VSENSE_PVCCFA_EHV_CPU1_DP ; 2 = PVCCFA_EHV_CPU1
PR574  Q_RES  100 1% CHIP  pkg 0402LF  page 284 : 1 = VSENSE_PVCCIN_CPU1_DN ; 2 = GND
PR578  Q_RES  100 1% CHIP  pkg 0402LF  page 284 : 1 = VSENSE_PVCCIN_CPU1_DP ; 2 = PVCCIN_CPU1
PR586  Q_RES  100 1% CHIP  pkg 0402LF  page 266 : 1 = VSENSE_PVCCFA_EHV_FIVRA_CPU0_DN ; 2 = GND
PR587  Q_RES  100 1% CHIP  pkg 0402LF  page 266 : 1 = VSENSE_PVCCFA_EHV_FIVRA_CPU0_DP ; 2 = PVCCFA_EHV_FIVRA_CPU0
PR591  Q_RES  100 1% CHIP  pkg 0402LF  page 278 : 1 = VSENSE_PVCCD_HV_CPU0_DN ; 2 = GND
PR592  Q_RES  100 1% CHIP  pkg 0402LF  page 278 : 1 = VSENSE_PVCCD_HV_CPU0_DP ; 2 = PVCCD_HV_CPU0
PR632  Q_RES  0 5% EMPTY  pkg 0402LF  page 271 : 1 = P3V3 ; 2 = PVCCFA_EHV_FIVRA_CPU0_PVCC1
PR633  Q_RES  0 5% EMPTY  pkg 0402LF  page 271 : 1 = P3V3 ; 2 = PVCCFA_EHV_FIVRA_CPU0_PVCC2
PR634  Q_RES  10K 1% EMPTY  pkg 0402LF  page 278 : 1 = PVCCD_HV_CPU0_ATSEN ; 2 = GND
PR637  Q_RES  10K 1% EMPTY  pkg 0402LF  page 284 : 1 = PVCCIN_CPU1_ATSEN ; 2 = GND
PR639  Q_RES  0 5% CHIP  pkg 0402LF  page 285 : 1 = P5V ; 2 = PVCCIN_CPU1_PVCC
PR640  Q_RES  0 5% EMPTY  pkg 0402LF  page 285 : 1 = P3V3 ; 2 = PVCCIN_CPU1_PVCC
PR665  Q_RES  10K 1% EMPTY  pkg 0402LF  page 292 : 1 = PVCCINFAON_CPU1_ATSEN ; 2 = GND
PR667  Q_RES  10K 1% EMPTY  pkg 0402LF  page 292 : 1 = PVCCFA_EHV_CPU1_BTSEN ; 2 = GND
PR678  Q_RES  0 5% CHIP  pkg 0402LF  page 294 : 1 = P5V ; 2 = PVCCFA_EHV_CPU1_PVCC
PR699  Q_RES  0 5% EMPTY  pkg 0402LF  page 294 : 1 = P3V3 ; 2 = PVCCFA_EHV_CPU1_PVCC
PR701  Q_RES  0 5% CHIP  pkg 0402LF  page 289 : 1 = P5V ; 2 = PVCCFA_EHV_FIVRA_CPU1_PVCC1
PR702  Q_RES  0 5% CHIP  pkg 0402LF  page 289 : 1 = P5V ; 2 = PVCCFA_EHV_FIVRA_CPU1_PVCC2
PR703  Q_RES  0 5% EMPTY  pkg 0402LF  page 289 : 1 = P3V3 ; 2 = PVCCFA_EHV_FIVRA_CPU1_PVCC1
PR704  Q_RES  0 5% EMPTY  pkg 0402LF  page 289 : 1 = P3V3 ; 2 = PVCCFA_EHV_FIVRA_CPU1_PVCC2
PR705  Q_RES  10K 1% EMPTY  pkg 0402LF  page 296 : 1 = PVCCD_HV_CPU1_ATSEN ; 2 = GND
PR830  Q_RES  15K 0.1% CHIP  pkg 0402LF  page 259 : 1 = P3V3_AUX_FB ; 2 = GND
PR831  Q_RES  47K 0.1% CHIP  pkg 0402LF  page 259 : 1 = P3V3_AUX_FB ; 2 = P3V3_AUX
PR832  Q_RES  0 5% CHIP  pkg 0402LF  page 259 : 1 = P3V3_AUX_MODE ; 2 = GND
PR833  Q_RES  1.5K 1% EMPTY  pkg 0402LF  page 259 : 1 = P3V3_AUX_SS ; 2 = GND
PR834  Q_RES  21.5K 1% CHIP  pkg 0402LF  page 259 : 1 = P3V3_AUX_ILIM ; 2 = GND
PR835  Q_RES  0 5% CHIP  pkg 0402LF  page 259 : 1 = SW_P3V3_AUX_BOOT ; 2 = SW_P3V3_AUX_BOOT_R
PR836  Q_RES  1K 1% EMPTY  pkg 0402LF  page 259 : 1 = P3V3_AUX_VOS ; 2 = P3V3_AUX
PR1101  Q_RES  2K 0.1% CHIP  pkg 0402LF  page 302 : 1 = HSC_IMON ; 2 = AGND_HSC
PR1131  Q_RES  2K 0.1% CHIP  pkg 0402LF  page 301 : 1 = HSC_CS ; 2 = AGND_HSC
PR1133  Q_RES  2K 0.1% CHIP  pkg 0402LF  page 301 : 1 = HSC_IMON ; 2 = AGND_HSC
PR1134  Q_RES  120K 1% CHIP  pkg 0402LF  page 302 : 1 = AGND_HSC ; 2 = HSC_MODE_1
PR1297  Q_RES  8.87K 1% EMPTY  pkg 0402LF  page 272 : 1 = PVCCFA_EHV_FIVRA_CPU0_LSET4 ; 2 = GND
PR1298  Q_RES  8.87K 1% EMPTY  pkg 0402LF  page 272 : 1 = PVCCFA_EHV_FIVRA_CPU0_LSET3 ; 2 = GND
PR1299  Q_RES  2.2 1% CHIP  pkg 0402LF  page 272 : 1 = PVCCFA_EHV_FIVRA_CPU0_PVCC1 ; 2 = PVCCFA_EHV_FIVRA_CPU0_VDD3
PR1300  Q_RES  2.2 1% CHIP  pkg 0402LF  page 272 : 1 = PVCCFA_EHV_FIVRA_CPU0_PVCC2 ; 2 = PVCCFA_EHV_FIVRA_CPU0_VDD4
PR1301  Q_RES  60.4K 1% CHIP  pkg 0402LF  page 282 : 1 = PVNN_MAIN_CPU0_MODE ; 2 = GND
PR1303  Q_RES  22.6K 1% CHIP  pkg 0402LF  page 282 : 1 = PVNN_MAIN_CPU0_CS ; 2 = GND
PR1304  Q_RES  8.87K 1% EMPTY  pkg 0402LF  page 290 : 1 = PVCCFA_EHV_FIVRA_CPU1_LSET4 ; 2 = GND
PR1305  Q_RES  8.87K 1% EMPTY  pkg 0402LF  page 290 : 1 = PVCCFA_EHV_FIVRA_CPU1_LSET3 ; 2 = GND
PR1306  Q_RES  2.2 1% CHIP  pkg 0402LF  page 290 : 1 = PVCCFA_EHV_FIVRA_CPU1_PVCC1 ; 2 = PVCCFA_EHV_FIVRA_CPU1_VDD3
PR1307  Q_RES  2.2 1% CHIP  pkg 0402LF  page 290 : 1 = PVCCFA_EHV_FIVRA_CPU1_PVCC2 ; 2 = PVCCFA_EHV_FIVRA_CPU1_VDD4
PR1310  Q_RES  11.3K 0.1% CHIP  pkg 0402LF  page 281 : 1 = PVPP_HBM_CPU0_FB ; 2 = SH_PVPP_HBM_CPU0_N
PR1311  Q_RES  0 5% CHIP  pkg 0402LF  page 278 : 1 = PVCCD_HV_CPU0_ISYS_R ; 2 = GND
PR1314  Q_RES  11.3K 0.1% CHIP  pkg 0402LF  page 299 : 1 = PVPP_HBM_CPU1_FB ; 2 = SH_PVPP_HBM_CPU1_N
PR1315  Q_RES  0 5% CHIP  pkg 0402LF  page 296 : 1 = PVCCD_HV_CPU1_ISYS_R ; 2 = GND
PR1322  Q_RES  0 5% CHIP  pkg 0402LF  page 271 : 1 = PVCCFA_EHV_FIVRA_CPU0_VOS1 ; 2 = PVCCFA_EHV_FIVRA_CPU0
PR1323  Q_RES  0 5% CHIP  pkg 0402LF  page 271 : 1 = PVCCFA_EHV_FIVRA_CPU0_VOS2 ; 2 = PVCCFA_EHV_FIVRA_CPU0
PR1324  Q_RES  0 5% CHIP  pkg 0402LF  page 272 : 1 = PVCCFA_EHV_FIVRA_CPU0_VOS3 ; 2 = PVCCFA_EHV_FIVRA_CPU0
PR1325  Q_RES  0 5% CHIP  pkg 0402LF  page 272 : 1 = PVCCFA_EHV_FIVRA_CPU0_VOS4 ; 2 = PVCCFA_EHV_FIVRA_CPU0
PR1326  Q_RES  0 5% CHIP  pkg 0402LF  page 262 : 1 = P3V3_AUX ; 2 = P1V05_PCH_AUX_VCC
PR1327  Q_RES  8.45K 1% CHIP  pkg 0402LF  page 262 : 1 = P1V05_PCH_AUX_CS ; 2 = GND
PR1328  Q_RES  7.32K 0.1% CHIP  pkg 0402LF  page 262 : 1 = P1V05_PCH_AUX_FB ; 2 = SH_P1V05_PCH_AUX_P
PR1329  Q_RES  5.1 5% CHIP  pkg 0402LF  page 263 : 1 = PVCC1_AUX ; 2 = P1V8_PCH_AUX_VCC
PR1330  Q_RES  150K 1% CHIP  pkg 0402LF  page 263 : 1 = P1V8_PCH_AUX_MODE ; 2 = GND
PR1331  Q_RES  0 5% CHIP  pkg 0402LF  page 289 : 1 = PVCCFA_EHV_FIVRA_CPU1_VOS1 ; 2 = PVCCFA_EHV_FIVRA_CPU1
PR1332  Q_RES  0 5% CHIP  pkg 0402LF  page 289 : 1 = PVCCFA_EHV_FIVRA_CPU1_VOS2 ; 2 = PVCCFA_EHV_FIVRA_CPU1
